# T6G (Grand Teton) — schematic netlist excerpt (pin names and nets, part order shuffled) for the footprints in the layout excerpt that follows; sources: Cadence DE-HDL packaged netlist, KiCad conversion of 04192023_DAF0TMB3IC0_F0TG_MB_C_brd_V02_OCP.brd

H96  HOLE  EMPTY  pkg TH  page 230 : \1\ = GND
R647  Q_RES  0 5% CHIP  pkg 0402LF  page 362 : A = P0V9_RETIMER_CPU0_PMSDA ; B = P0V9_RETIMER_CPU0_PMSDA_R
R8124  Q_RES  33.2 1% CHIP  pkg 0402LF  page 268 : A = IRQ_UV_DETECT_R2_N ; B = IRQ_UV_DETECT_N

(kicad_pcb
	(version 20260206)
	(generator "pcbnew")
	(generator_version "10.0")
	(general
		(thickness 1.6)
		(legacy_teardrops no)
	)
	(paper "A4")
	(title_block
		(title "04192023_DAF0TMB3IC0_F0TG_MB_C_brd_V02_OCP.brd")
		(comment 1 "Grand Teton / footprints 2375-2377 of 8354")
	)
	(layers
		(0 "F.Cu" signal "TOP")
		(4 "In1.Cu" signal "GND")
		(6 "In2.Cu" signal "IN1")
		(8 "In3.Cu" signal "GND1")
		(10 "In4.Cu" signal "IN2")
		(12 "In5.Cu" signal "GND2")
		(14 "In6.Cu" signal "IN3")
		(16 "In7.Cu" signal "GND3")
		(18 "In8.Cu" signal "VCC")
		(20 "In9.Cu" signal "VCC1")
		(22 "In10.Cu" signal "GND4")
		(24 "In11.Cu" signal "IN4")
		(26 "In12.Cu" signal "GND5")
		(28 "In13.Cu" signal "IN5")
		(30 "In14.Cu" signal "GND6")
		(32 "In15.Cu" signal "IN6")
		(34 "In16.Cu" signal "GND7")
		(2 "B.Cu" signal "BOTTOM")
		(9 "F.Adhes" user "F.Adhesive")
		(11 "B.Adhes" user "B.Adhesive")
		(13 "F.Paste" user "Package Geometry/Pastemask Top")
		(15 "B.Paste" user "Package Geometry/Pastemask Bottom")
		(5 "F.SilkS" user "Ref Des/Silkscreen Top")
		(7 "B.SilkS" user "Ref Des/Silkscreen Bottom")
		(1 "F.Mask" user "Board Geometry/Soldermask Top")
		(3 "B.Mask" user "Board Geometry/Soldermask Bottom")
		(17 "Dwgs.User" user "User.Drawings")
		(19 "Cmts.User" user "User.Comments")
		(21 "Eco1.User" user "User.Eco1")
		(23 "Eco2.User" user "User.Eco2")
		(25 "Edge.Cuts" user "Board Geometry/Outline")
		(27 "Margin" user)
		(31 "F.CrtYd" user "Package Geometry/Place Bound Top")
		(29 "B.CrtYd" user "Package Geometry/Place Bound Bottom")
		(35 "F.Fab" user "Ref Des/Assembly Top")
		(33 "B.Fab" user "Ref Des/Assembly Bottom")
	)
	(footprint ""
		(layer "F.Cu")
		(at 443.347602 -429.37811 -90)
		(property "Reference" "R647"
			(at 0 0 270)
			(layer "F.SilkS")
			(hide yes)
			(effects
				(font
					(size 1.27 1.27)
				)
			)
		)
		(property "Value" ""
			(at 0 0 270)
			(layer "F.Fab")
			(effects
				(font
					(size 1.27 1.27)
				)
			)
		)
		(duplicate_pad_numbers_are_jumpers no)
		(fp_line
			(start -0.7874 0.4064)
			(end -0.7874 -0.4064)
			(stroke
				(width 0.1524)
				(type default)
			)
			(layer "F.SilkS")
		)
		(fp_line
			(start 0.7874 0.4064)
			(end -0.7874 0.4064)
			(stroke
				(width 0.1524)
				(type default)
			)
			(layer "F.SilkS")
		)
		(fp_line
			(start -0.7874 -0.4064)
			(end 0.7874 -0.4064)
			(stroke
				(width 0.1524)
				(type default)
			)
			(layer "F.SilkS")
		)
		(fp_line
			(start 0.7874 -0.4064)
			(end 0.7874 0.4064)
			(stroke
				(width 0.1524)
				(type default)
			)
			(layer "F.SilkS")
		)
		(fp_line
			(start -0.67945 0.3048)
			(end -0.67945 -0.305054)
			(stroke
				(width 0.1)
				(type default)
			)
			(layer "F.Fab")
		)
		(fp_line
			(start -0.12065 0.3048)
			(end -0.67945 0.3048)
			(stroke
				(width 0.1)
				(type default)
			)
			(layer "F.Fab")
		)
		(fp_line
			(start 0.120396 0.3048)
			(end 0.120396 0.2794)
			(stroke
				(width 0.1)
				(type default)
			)
			(layer "F.Fab")
		)
		(fp_line
			(start 0.67945 0.3048)
			(end 0.120396 0.3048)
			(stroke
				(width 0.1)
				(type default)
			)
			(layer "F.Fab")
		)
		(fp_line
			(start -0.12065 0.2794)
			(end -0.12065 0.3048)
			(stroke
				(width 0.1)
				(type default)
			)
			(layer "F.Fab")
		)
		(fp_line
			(start 0.120396 0.2794)
			(end -0.12065 0.2794)
			(stroke
				(width 0.1)
				(type default)
			)
			(layer "F.Fab")
		)
		(fp_line
			(start -0.12065 -0.2794)
			(end 0.12065 -0.2794)
			(stroke
				(width 0.1)
				(type default)
			)
			(layer "F.Fab")
		)
		(fp_line
			(start 0.12065 -0.2794)
			(end 0.12065 -0.3048)
			(stroke
				(width 0.1)
				(type default)
			)
			(layer "F.Fab")
		)
		(fp_line
			(start 0.12065 -0.3048)
			(end 0.67945 -0.3048)
			(stroke
				(width 0.1)
				(type default)
			)
			(layer "F.Fab")
		)
		(fp_line
			(start 0.67945 -0.3048)
			(end 0.67945 0.3048)
			(stroke
				(width 0.1)
				(type default)
			)
			(layer "F.Fab")
		)
		(fp_line
			(start -0.67945 -0.305054)
			(end -0.12065 -0.305054)
			(stroke
				(width 0.1)
				(type default)
			)
			(layer "F.Fab")
		)
		(fp_line
			(start -0.12065 -0.305054)
			(end -0.12065 -0.2794)
			(stroke
				(width 0.1)
				(type default)
			)
			(layer "F.Fab")
		)
		(pad "1" smd circle
			(at -0.40005 0 270)
			(size 0 0)
			(layers "F.Cu" "F.Mask" "F.Paste")
			(net "P0V9_RETIMER_CPU0_PMSDA")
		)
		(pad "2" smd circle
			(at 0.40005 0 270)
			(size 0 0)
			(layers "F.Cu" "F.Mask" "F.Paste")
			(net "P0V9_RETIMER_CPU0_PMSDA_R")
		)
	)
	(footprint ""
		(layer "F.Cu")
		(at 464.799934 -22.29993)
		(property "Reference" "H96"
			(at -5.137658 -5.653532 0)
			(unlocked yes)
			(layer "F.SilkS")
			(effects
				(font
					(size 0.7874 0.5842)
					(thickness 0.1524)
				)
				(justify left)
			)
		)
		(property "Value" ""
			(at 0 0 0)
			(layer "F.Fab")
			(effects
				(font
					(size 1.27 1.27)
				)
			)
		)
		(duplicate_pad_numbers_are_jumpers no)
		(pad "1" thru_hole circle
			(at 0 0)
			(size 10.0076 10.0076)
			(drill 5.6134)
			(layers "*.Cu" "*.Mask")
			(remove_unused_layers no)
			(net "GND")
			(clearance -1.9431)
		)
	)
	(footprint ""
		(layer "F.Cu")
		(at 142.367 -121.285)
		(property "Reference" "R8124"
			(at 0 0 0)
			(layer "F.SilkS")
			(hide yes)
			(effects
				(font
					(size 1.27 1.27)
				)
			)
		)
		(property "Value" ""
			(at 0 0 0)
			(layer "F.Fab")
			(effects
				(font
					(size 1.27 1.27)
				)
			)
		)
		(duplicate_pad_numbers_are_jumpers no)
		(fp_line
			(start -0.7874 -0.4064)
			(end 0.7874 -0.4064)
			(stroke
				(width 0.1524)
				(type default)
			)
			(layer "F.SilkS")
		)
		(fp_line
			(start -0.7874 0.4064)
			(end -0.7874 -0.4064)
			(stroke
				(width 0.1524)
				(type default)
			)
			(layer "F.SilkS")
		)
		(fp_line
			(start 0.7874 -0.4064)
			(end 0.7874 0.4064)
			(stroke
				(width 0.1524)
				(type default)
			)
			(layer "F.SilkS")
		)
		(fp_line
			(start 0.7874 0.4064)
			(end -0.7874 0.4064)
			(stroke
				(width 0.1524)
				(type default)
			)
			(layer "F.SilkS")
		)
		(fp_line
			(start -0.67945 -0.305054)
			(end -0.12065 -0.305054)
			(stroke
				(width 0.1)
				(type default)
			)
			(layer "F.Fab")
		)
		(fp_line
			(start -0.67945 0.3048)
			(end -0.67945 -0.305054)
			(stroke
				(width 0.1)
				(type default)
			)
			(layer "F.Fab")
		)
		(fp_line
			(start -0.12065 -0.305054)
			(end -0.12065 -0.2794)
			(stroke
				(width 0.1)
				(type default)
			)
			(layer "F.Fab")
		)
		(fp_line
			(start -0.12065 -0.2794)
			(end 0.12065 -0.2794)
			(stroke
				(width 0.1)
				(type default)
			)
			(layer "F.Fab")
		)
		(fp_line
			(start -0.12065 0.2794)
			(end -0.12065 0.3048)
			(stroke
				(width 0.1)
				(type default)
			)
			(layer "F.Fab")
		)
		(fp_line
			(start -0.12065 0.3048)
			(end -0.67945 0.3048)
			(stroke
				(width 0.1)
				(type default)
			)
			(layer "F.Fab")
		)
		(fp_line
			(start 0.120396 0.2794)
			(end -0.12065 0.2794)
			(stroke
				(width 0.1)
				(type default)
			)
			(layer "F.Fab")
		)
		(fp_line
			(start 0.120396 0.3048)
			(end 0.120396 0.2794)
			(stroke
				(width 0.1)
				(type default)
			)
			(layer "F.Fab")
		)
		(fp_line
			(start 0.12065 -0.3048)
			(end 0.67945 -0.3048)
			(stroke
				(width 0.1)
				(type default)
			)
			(layer "F.Fab")
		)
		(fp_line
			(start 0.12065 -0.2794)
			(end 0.12065 -0.3048)
			(stroke
				(width 0.1)
				(type default)
			)
			(layer "F.Fab")
		)
		(fp_line
			(start 0.67945 -0.3048)
			(end 0.67945 0.3048)
			(stroke
				(width 0.1)
				(type default)
			)
			(layer "F.Fab")
		)
		(fp_line
			(start 0.67945 0.3048)
			(end 0.120396 0.3048)
			(stroke
				(width 0.1)
				(type default)
			)
			(layer "F.Fab")
		)
		(pad "1" smd circle
			(at -0.40005 0)
			(size 0 0)
			(layers "F.Cu" "F.Mask" "F.Paste")
			(net "IRQ_UV_DETECT_R2_N")
		)
		(pad "2" smd circle
			(at 0.40005 0)
			(size 0 0)
			(layers "F.Cu" "F.Mask" "F.Paste")
			(net "IRQ_UV_DETECT_N")
		)
	)
)
